(kicad_pcb
	(version 20221018)
	(generator pcbnew)
	(general
    (thickness 1.7403)
  )
	(paper "A4")
	(title_block
    (title "Data Center RDIMM DDR4 Tester")
    (date "2024-09-30")
    (rev "1.2.4")
		(comment 9 "footprints 678-687 of 690")
	)
	(layers
    (0 "F.Cu" signal)
    (1 "In1.Cu" power)
    (2 "In2.Cu" signal)
    (3 "In3.Cu" power)
    (4 "In4.Cu" power)
    (5 "In5.Cu" signal)
    (6 "In6.Cu" power)
    (7 "In7.Cu" signal)
    (8 "In8.Cu" power)
    (9 "In9.Cu" signal)
    (10 "In10.Cu" power)
    (31 "B.Cu" signal)
    (32 "B.Adhes" user "B.Adhesive")
    (33 "F.Adhes" user "F.Adhesive")
    (34 "B.Paste" user)
    (35 "F.Paste" user)
    (36 "B.SilkS" user "B.Silkscreen")
    (37 "F.SilkS" user "F.Silkscreen")
    (38 "B.Mask" user)
    (39 "F.Mask" user)
    (40 "Dwgs.User" user "User.Drawings")
    (41 "Cmts.User" user "User.Comments")
    (42 "Eco1.User" user "User.Eco1")
    (43 "Eco2.User" user "User.Eco2")
    (44 "Edge.Cuts" user)
    (45 "Margin" user)
    (46 "B.CrtYd" user "B.Courtyard")
    (47 "F.CrtYd" user "F.Courtyard")
    (48 "B.Fab" user)
    (49 "F.Fab" user)
  )
	(footprint "data-center-rdimm-ddr4-tester-footprints:C_0402_1005Metric" (layer "B.Cu")
    (at 134.875 105.675)
    (descr "Capacitor SMD 0402")
    (tags "capacitor SMD 0402")
    (property "Author" "Antmicro")
    (property "Dielectric" "X5R")
    (property "License" "Apache-2.0")
    (property "MPN" "GRM155R61H104KE14D")
    (property "Manufacturer" "Murata")
    (property "Sheetfile" "supply.kicad_sch")
    (property "Sheetname" "Supply")
    (property "Val" "100n")
    (property "Voltage" "50V")
    (property "ki_description" " ")
    (attr smd)
    (fp_text reference "C232" (at 3.645 0.375 180) (layer "B.SilkS")
        (effects (font (size 0.7 0.7) (thickness 0.15)) (justify left bottom mirror))
    )
    (fp_text value "C_100n_0402" (at 0 -1.4 180) (layer "B.Fab") hide
        (effects (font (size 0.7 0.7) (thickness 0.15)) (justify left bottom mirror))
    )
    (fp_text user "Author: Antmicro" (at -0.932 -4.17 180) (layer "B.Fab") hide
        (effects (font (size 0.7 0.7) (thickness 0.15)) (justify left bottom mirror))
    )
    (fp_text user "${REFERENCE}" (at -0.932 -3.168 180) (layer "B.Fab") hide
        (effects (font (size 0.7 0.7) (thickness 0.15)) (justify left bottom mirror))
    )
    (fp_text user "License: Apache-2.0" (at -0.932 -5.17 180) (layer "B.Fab") hide
        (effects (font (size 0.7 0.7) (thickness 0.15)) (justify left bottom mirror))
    )
    (fp_rect (start -0.94 0.47) (end 0.94 -0.47)
      (stroke (width 0.05) (type solid)) (fill none) (layer "B.CrtYd"))
    (fp_rect (start -0.499 0.249) (end 0.499 -0.249)
      (stroke (width 0.15) (type solid)) (fill none) (layer "B.Fab"))
    (pad "1" smd roundrect (at -0.484 0) (size 0.59 0.64) (layers "B.Cu" "B.Paste" "B.Mask") (roundrect_rratio 0.25)
      (net 307 "5V0_SYS") (pintype "passive"))
    (pad "2" smd roundrect (at 0.484 0) (size 0.59 0.64) (layers "B.Cu" "B.Paste" "B.Mask") (roundrect_rratio 0.25)
      (net 9 "GND") (pintype "passive"))
  )
	(footprint "data-center-rdimm-ddr4-tester-footprints:R_0402_1005Metric" (layer "B.Cu")
    (at 179.51 124.8 180)
    (descr "Resistor SMD 0402")
    (tags "resistor SMD 0402")
    (property "Author" "Antmicro")
    (property "License" "Apache-2.0")
    (property "MPN" "CR0402-FX-2492GLF")
    (property "Manufacturer" "Bourns")
    (property "Sheetfile" "ethernet.kicad_sch")
    (property "Sheetname" "Ethernet")
    (property "Tolerance" "1%")
    (property "Val" "24k9")
    (property "ki_description" "24k9 resistor in 0402 package with 1% tolerance")
    (attr smd)
    (fp_text reference "R175" (at -8.74 4.01) (layer "B.SilkS")
        (effects (font (size 0.7 0.7) (thickness 0.15)) (justify left bottom mirror))
    )
    (fp_text value "R_24k9_0402" (at 0 -1.4) (layer "B.Fab") hide
        (effects (font (size 0.7 0.7) (thickness 0.15)) (justify left bottom mirror))
    )
    (fp_text user "License: Apache-2.0" (at -0.95 -5.169) (layer "B.Fab") hide
        (effects (font (size 0.7 0.7) (thickness 0.15)) (justify left bottom mirror))
    )
    (fp_text user "${REFERENCE}" (at -0.95 -3.168) (layer "B.Fab") hide
        (effects (font (size 0.7 0.7) (thickness 0.15)) (justify left bottom mirror))
    )
    (fp_text user "Author: Antmicro" (at -0.95 -4.169) (layer "B.Fab") hide
        (effects (font (size 0.7 0.7) (thickness 0.15)) (justify left bottom mirror))
    )
    (fp_rect (start -0.93 0.47) (end 0.93 -0.47)
      (stroke (width 0.05) (type solid)) (fill none) (layer "B.CrtYd"))
    (fp_rect (start -0.5 0.25) (end 0.5 -0.25)
      (stroke (width 0.15) (type solid)) (fill none) (layer "B.Fab"))
    (pad "1" smd roundrect (at -0.485 0 180) (size 0.59 0.64) (layers "B.Cu" "B.Paste" "B.Mask") (roundrect_rratio 0.25)
      (net 610 "/Ethernet/DEN") (pintype "passive"))
    (pad "2" smd roundrect (at 0.485 0 180) (size 0.59 0.64) (layers "B.Cu" "B.Paste" "B.Mask") (roundrect_rratio 0.25)
      (net 360 "/Ethernet/VDD") (pintype "passive"))
  )
	(footprint "data-center-rdimm-ddr4-tester-footprints:R_0402_1005Metric" (layer "B.Cu")
    (at 176.25 128.105 180)
    (descr "Resistor SMD 0402")
    (tags "resistor SMD 0402")
    (property "Author" "Antmicro")
    (property "DNP" "DNP")
    (property "License" "Apache-2.0")
    (property "MPN" "CR0402-FX-1002GLF")
    (property "Manufacturer" "Bourns")
    (property "Sheetfile" "ethernet.kicad_sch")
    (property "Sheetname" "Ethernet")
    (property "Tolerance" "1%")
    (property "Val" "10k")
    (property "dnp" "")
    (property "exclude_from_bom" "")
    (property "ki_description" "10k resistor in 0402 package with 1% tolerance")
    (attr exclude_from_pos_files exclude_from_bom)
    (fp_text reference "R177" (at 0.73 -0.445) (layer "B.SilkS")
        (effects (font (size 0.7 0.7) (thickness 0.15)) (justify left bottom mirror))
    )
    (fp_text value "R_10k_0402" (at 0 -1.4) (layer "B.Fab") hide
        (effects (font (size 0.7 0.7) (thickness 0.15)) (justify left bottom mirror))
    )
    (fp_text user "Author: Antmicro" (at -0.95 -4.169) (layer "B.Fab") hide
        (effects (font (size 0.7 0.7) (thickness 0.15)) (justify left bottom mirror))
    )
    (fp_text user "License: Apache-2.0" (at -0.95 -5.169) (layer "B.Fab") hide
        (effects (font (size 0.7 0.7) (thickness 0.15)) (justify left bottom mirror))
    )
    (fp_text user "${REFERENCE}" (at -0.95 -3.168) (layer "B.Fab") hide
        (effects (font (size 0.7 0.7) (thickness 0.15)) (justify left bottom mirror))
    )
    (fp_rect (start -0.93 0.47) (end 0.93 -0.47)
      (stroke (width 0.05) (type solid)) (fill none) (layer "B.CrtYd"))
    (fp_rect (start -0.5 0.25) (end 0.5 -0.25)
      (stroke (width 0.15) (type solid)) (fill none) (layer "B.Fab"))
    (pad "1" smd roundrect (at -0.485 0 180) (size 0.59 0.64) (layers "B.Cu" "B.Paste" "B.Mask") (roundrect_rratio 0.25)
      (net 619 "/Ethernet/TPH") (pintype "passive"))
    (pad "2" smd roundrect (at 0.485 0 180) (size 0.59 0.64) (layers "B.Cu" "B.Paste" "B.Mask") (roundrect_rratio 0.25)
      (net 360 "/Ethernet/VDD") (pintype "passive"))
  )
	(footprint "data-center-rdimm-ddr4-tester-footprints:C_0201" (layer "B.Cu")
    (at 196.2 96.55)
    (descr "Capacitor SMD 0201")
    (tags "capacitor SMD 0201")
    (property "Author" "Antmicro")
    (property "Dielectric" "")
    (property "License" "Apache-2.0")
    (property "MPN" "CC0201KRX6S5BB104")
    (property "Manufacturer" "Yaego")
    (property "Sheetfile" "fpga-power.kicad_sch")
    (property "Sheetname" "FPGA power")
    (property "Val" "100n")
    (property "Voltage" "")
    (property "ki_description" " ")
    (attr smd)
    (fp_text reference "C250" (at 3.5 0.38 180) (layer "B.SilkS")
        (effects (font (size 0.7 0.7) (thickness 0.15)) (justify left bottom mirror))
    )
    (fp_text value "C_100n_0201" (at 0 -1.4 180) (layer "B.Fab") hide
        (effects (font (size 0.7 0.7) (thickness 0.15)) (justify left bottom mirror))
    )
    (fp_text user "Author: Antmicro" (at -0.72 -5.4 180) (layer "B.Fab") hide
        (effects (font (size 0.7 0.7) (thickness 0.15)) (justify left bottom mirror))
    )
    (fp_text user "License: Apache-2.0" (at -0.72 -4.4 180) (layer "B.Fab") hide
        (effects (font (size 0.7 0.7) (thickness 0.15)) (justify left bottom mirror))
    )
    (fp_text user "${REFERENCE}" (at -0.72 -3.4 180) (layer "B.Fab") hide
        (effects (font (size 0.7 0.7) (thickness 0.15)) (justify left bottom mirror))
    )
    (fp_rect (start -0.72 0.38) (end 0.72 -0.38)
      (stroke (width 0.05) (type solid)) (fill none) (layer "B.CrtYd"))
    (fp_rect (start 0.3 -0.15) (end -0.301 0.149)
      (stroke (width 0.15) (type solid)) (fill none) (layer "B.Fab"))
    (pad "" smd roundrect (at -0.349 0.002) (size 0.318 0.36) (layers "B.Paste") (roundrect_rratio 0.25))
    (pad "" smd roundrect (at 0.341 0.002) (size 0.318 0.36) (layers "B.Paste") (roundrect_rratio 0.25))
    (pad "1" smd roundrect (at -0.321 0.002) (size 0.46 0.4) (layers "B.Cu" "B.Mask") (roundrect_rratio 0.25)
      (net 306 "1V2_SYS") (pintype "passive"))
    (pad "2" smd roundrect (at 0.32 0.002) (size 0.46 0.4) (layers "B.Cu" "B.Mask") (roundrect_rratio 0.25)
      (net 9 "GND") (pintype "passive"))
  )
	(footprint "data-center-rdimm-ddr4-tester-footprints:C_0402_1005Metric" (layer "B.Cu")
    (at 165.9 108.75 -90)
    (descr "Capacitor SMD 0402")
    (tags "capacitor SMD 0402")
    (property "Author" "Antmicro")
    (property "DNP" "DNP")
    (property "Dielectric" "X5R")
    (property "License" "Apache-2.0")
    (property "MPN" "GRM155R61H104KE14D")
    (property "Manufacturer" "Murata")
    (property "Sheetfile" "ethernet.kicad_sch")
    (property "Sheetname" "Ethernet")
    (property "Val" "100n")
    (property "Voltage" "50V")
    (property "dnp" "")
    (property "exclude_from_bom" "")
    (property "ki_description" " ")
    (attr exclude_from_pos_files exclude_from_bom)
    (fp_text reference "C292" (at -1.38 -1.42 90) (layer "B.SilkS")
        (effects (font (size 0.7 0.7) (thickness 0.15)) (justify left bottom mirror))
    )
    (fp_text value "C_100n_0402" (at 0 -1.4 90) (layer "B.Fab") hide
        (effects (font (size 0.7 0.7) (thickness 0.15)) (justify left bottom mirror))
    )
    (fp_text user "${REFERENCE}" (at -0.932 -3.168 90) (layer "B.Fab") hide
        (effects (font (size 0.7 0.7) (thickness 0.15)) (justify left bottom mirror))
    )
    (fp_text user "Author: Antmicro" (at -0.932 -4.17 90) (layer "B.Fab") hide
        (effects (font (size 0.7 0.7) (thickness 0.15)) (justify left bottom mirror))
    )
    (fp_text user "License: Apache-2.0" (at -0.932 -5.17 90) (layer "B.Fab") hide
        (effects (font (size 0.7 0.7) (thickness 0.15)) (justify left bottom mirror))
    )
    (fp_rect (start -0.94 0.47) (end 0.94 -0.47)
      (stroke (width 0.05) (type solid)) (fill none) (layer "B.CrtYd"))
    (fp_rect (start -0.499 0.249) (end 0.499 -0.249)
      (stroke (width 0.15) (type solid)) (fill none) (layer "B.Fab"))
    (pad "1" smd roundrect (at -0.484 0 270) (size 0.59 0.64) (layers "B.Cu" "B.Paste" "B.Mask") (roundrect_rratio 0.25)
      (net 143 "3V3_SYS") (pintype "passive"))
    (pad "2" smd roundrect (at 0.484 0 270) (size 0.59 0.64) (layers "B.Cu" "B.Paste" "B.Mask") (roundrect_rratio 0.25)
      (net 9 "GND") (pintype "passive"))
  )
	(footprint "data-center-rdimm-ddr4-tester-footprints:R_0402_1005Metric" (layer "B.Cu")
    (at 180.075 133.1 180)
    (descr "Resistor SMD 0402")
    (tags "resistor SMD 0402")
    (property "Author" "Antmicro")
    (property "Current" "1A")
    (property "License" "Apache-2.0")
    (property "MPN" "ERJ2GE0R00X")
    (property "Manufacturer" "Panasonic")
    (property "Sheetfile" "ethernet.kicad_sch")
    (property "Sheetname" "Ethernet")
    (property "Tolerance" "")
    (property "Val" "0R")
    (property "ki_description" "0R resistor in 0402 package with unspecified tolerance")
    (attr smd)
    (fp_text reference "R178" (at -1.385 0.48) (layer "B.SilkS")
        (effects (font (size 0.7 0.7) (thickness 0.15)) (justify left bottom mirror))
    )
    (fp_text value "R_0R_0402" (at 0 -1.4) (layer "B.Fab") hide
        (effects (font (size 0.7 0.7) (thickness 0.15)) (justify left bottom mirror))
    )
    (fp_text user "${REFERENCE}" (at -0.95 -3.168) (layer "B.Fab") hide
        (effects (font (size 0.7 0.7) (thickness 0.15)) (justify left bottom mirror))
    )
    (fp_text user "License: Apache-2.0" (at -0.95 -5.169) (layer "B.Fab") hide
        (effects (font (size 0.7 0.7) (thickness 0.15)) (justify left bottom mirror))
    )
    (fp_text user "Author: Antmicro" (at -0.95 -4.169) (layer "B.Fab") hide
        (effects (font (size 0.7 0.7) (thickness 0.15)) (justify left bottom mirror))
    )
    (fp_rect (start -0.93 0.47) (end 0.93 -0.47)
      (stroke (width 0.05) (type solid)) (fill none) (layer "B.CrtYd"))
    (fp_rect (start -0.5 0.25) (end 0.5 -0.25)
      (stroke (width 0.15) (type solid)) (fill none) (layer "B.Fab"))
    (pad "1" smd roundrect (at -0.485 0 180) (size 0.59 0.64) (layers "B.Cu" "B.Paste" "B.Mask") (roundrect_rratio 0.25)
      (net 620 "/Ethernet/PG") (pintype "passive"))
    (pad "2" smd roundrect (at 0.485 0 180) (size 0.59 0.64) (layers "B.Cu" "B.Paste" "B.Mask") (roundrect_rratio 0.25)
      (net 615 "/Ethernet/POE_ACTIVE") (pintype "passive"))
  )
	(footprint "data-center-rdimm-ddr4-tester-footprints:C_0201" (layer "B.Cu")
    (at 173.15 86.65 180)
    (descr "Capacitor SMD 0201")
    (tags "capacitor SMD 0201")
    (property "Author" "Antmicro")
    (property "Dielectric" "")
    (property "License" "Apache-2.0")
    (property "MPN" "CC0201KRX6S5BB104")
    (property "Manufacturer" "Yaego")
    (property "Sheetfile" "fpga-power.kicad_sch")
    (property "Sheetname" "FPGA power")
    (property "Val" "100n")
    (property "Voltage" "")
    (property "ki_description" " ")
    (attr smd)
    (fp_text reference "C94" (at -1.05 -1.11) (layer "B.SilkS")
        (effects (font (size 0.7 0.7) (thickness 0.15)) (justify left bottom mirror))
    )
    (fp_text value "C_100n_0201" (at 0 -1.4) (layer "B.Fab") hide
        (effects (font (size 0.7 0.7) (thickness 0.15)) (justify left bottom mirror))
    )
    (fp_text user "License: Apache-2.0" (at -0.72 -4.4) (layer "B.Fab") hide
        (effects (font (size 0.7 0.7) (thickness 0.15)) (justify left bottom mirror))
    )
    (fp_text user "${REFERENCE}" (at -0.72 -3.4) (layer "B.Fab") hide
        (effects (font (size 0.7 0.7) (thickness 0.15)) (justify left bottom mirror))
    )
    (fp_text user "Author: Antmicro" (at -0.72 -5.4) (layer "B.Fab") hide
        (effects (font (size 0.7 0.7) (thickness 0.15)) (justify left bottom mirror))
    )
    (fp_rect (start -0.72 0.38) (end 0.72 -0.38)
      (stroke (width 0.05) (type solid)) (fill none) (layer "B.CrtYd"))
    (fp_rect (start 0.3 -0.15) (end -0.301 0.149)
      (stroke (width 0.15) (type solid)) (fill none) (layer "B.Fab"))
    (pad "" smd roundrect (at -0.349 0.002 180) (size 0.318 0.36) (layers "B.Paste") (roundrect_rratio 0.25))
    (pad "" smd roundrect (at 0.341 0.002 180) (size 0.318 0.36) (layers "B.Paste") (roundrect_rratio 0.25))
    (pad "1" smd roundrect (at -0.321 0.002 180) (size 0.46 0.4) (layers "B.Cu" "B.Mask") (roundrect_rratio 0.25)
      (net 143 "3V3_SYS") (pintype "passive"))
    (pad "2" smd roundrect (at 0.32 0.002 180) (size 0.46 0.4) (layers "B.Cu" "B.Mask") (roundrect_rratio 0.25)
      (net 9 "GND") (pintype "passive"))
  )
	(footprint "data-center-rdimm-ddr4-tester-footprints:C_0402_1005Metric" (layer "B.Cu")
    (at 193.1 90.83 90)
    (descr "Capacitor SMD 0402")
    (tags "capacitor SMD 0402")
    (property "Author" "Antmicro")
    (property "Dielectric" "")
    (property "License" "Apache-2.0")
    (property "MPN" "GRM155R61A475MEAAD")
    (property "Manufacturer" "Murata")
    (property "Sheetfile" "fpga-power.kicad_sch")
    (property "Sheetname" "FPGA power")
    (property "Val" "4u7")
    (property "Voltage" "")
    (property "ki_description" " ")
    (attr smd)
    (fp_text reference "C239" (at 1.72 2.79 90) (layer "B.SilkS")
        (effects (font (size 0.7 0.7) (thickness 0.15)) (justify left bottom mirror))
    )
    (fp_text value "C_4u7_0402" (at 0 -1.4 270) (layer "B.Fab") hide
        (effects (font (size 0.7 0.7) (thickness 0.15)) (justify left bottom mirror))
    )
    (fp_text user "${REFERENCE}" (at -0.932 -3.168 270) (layer "B.Fab") hide
        (effects (font (size 0.7 0.7) (thickness 0.15)) (justify left bottom mirror))
    )
    (fp_text user "License: Apache-2.0" (at -0.932 -5.17 270) (layer "B.Fab") hide
        (effects (font (size 0.7 0.7) (thickness 0.15)) (justify left bottom mirror))
    )
    (fp_text user "Author: Antmicro" (at -0.932 -4.17 270) (layer "B.Fab") hide
        (effects (font (size 0.7 0.7) (thickness 0.15)) (justify left bottom mirror))
    )
    (fp_rect (start -0.94 0.47) (end 0.94 -0.47)
      (stroke (width 0.05) (type solid)) (fill none) (layer "B.CrtYd"))
    (fp_rect (start -0.499 0.249) (end 0.499 -0.249)
      (stroke (width 0.15) (type solid)) (fill none) (layer "B.Fab"))
    (pad "1" smd roundrect (at -0.484 0 90) (size 0.59 0.64) (layers "B.Cu" "B.Paste" "B.Mask") (roundrect_rratio 0.25)
      (net 144 "1V8_SYS") (pintype "passive"))
    (pad "2" smd roundrect (at 0.484 0 90) (size 0.59 0.64) (layers "B.Cu" "B.Paste" "B.Mask") (roundrect_rratio 0.25)
      (net 9 "GND") (pintype "passive"))
  )
	(footprint "data-center-rdimm-ddr4-tester-footprints:C_0201" (layer "B.Cu")
    (at 176.075 90.45)
    (descr "Capacitor SMD 0201")
    (tags "capacitor SMD 0201")
    (property "Author" "Antmicro")
    (property "Dielectric" "")
    (property "License" "Apache-2.0")
    (property "MPN" "CC0201KRX6S5BB104")
    (property "Manufacturer" "Yaego")
    (property "Sheetfile" "fpga-power.kicad_sch")
    (property "Sheetname" "FPGA power")
    (property "Val" "100n")
    (property "Voltage" "")
    (property "ki_description" " ")
    (attr smd)
    (fp_text reference "C277" (at 1.345 -0.35 180) (layer "B.SilkS")
        (effects (font (size 0.7 0.7) (thickness 0.15)) (justify left bottom mirror))
    )
    (fp_text value "C_100n_0201" (at 0 -1.4 180) (layer "B.Fab") hide
        (effects (font (size 0.7 0.7) (thickness 0.15)) (justify left bottom mirror))
    )
    (fp_text user "Author: Antmicro" (at -0.72 -5.4 180) (layer "B.Fab") hide
        (effects (font (size 0.7 0.7) (thickness 0.15)) (justify left bottom mirror))
    )
    (fp_text user "${REFERENCE}" (at -0.72 -3.4 180) (layer "B.Fab") hide
        (effects (font (size 0.7 0.7) (thickness 0.15)) (justify left bottom mirror))
    )
    (fp_text user "License: Apache-2.0" (at -0.72 -4.4 180) (layer "B.Fab") hide
        (effects (font (size 0.7 0.7) (thickness 0.15)) (justify left bottom mirror))
    )
    (fp_rect (start -0.72 0.38) (end 0.72 -0.38)
      (stroke (width 0.05) (type solid)) (fill none) (layer "B.CrtYd"))
    (fp_rect (start 0.3 -0.15) (end -0.301 0.149)
      (stroke (width 0.15) (type solid)) (fill none) (layer "B.Fab"))
    (pad "" smd roundrect (at -0.349 0.002) (size 0.318 0.36) (layers "B.Paste") (roundrect_rratio 0.25))
    (pad "" smd roundrect (at 0.341 0.002) (size 0.318 0.36) (layers "B.Paste") (roundrect_rratio 0.25))
    (pad "1" smd roundrect (at -0.321 0.002) (size 0.46 0.4) (layers "B.Cu" "B.Mask") (roundrect_rratio 0.25)
      (net 77 "VDDQ") (pintype "passive"))
    (pad "2" smd roundrect (at 0.32 0.002) (size 0.46 0.4) (layers "B.Cu" "B.Mask") (roundrect_rratio 0.25)
      (net 9 "GND") (pintype "passive"))
  )
	(footprint "data-center-rdimm-ddr4-tester-footprints:R_0402_1005Metric" (layer "B.Cu")
    (at 176.25 130.125)
    (descr "Resistor SMD 0402")
    (tags "resistor SMD 0402")
    (property "Author" "Antmicro")
    (property "Current" "1A")
    (property "DNP" "DNP")
    (property "License" "Apache-2.0")
    (property "MPN" "ERJ2GE0R00X")
    (property "Manufacturer" "Panasonic")
    (property "Sheetfile" "ethernet.kicad_sch")
    (property "Sheetname" "Ethernet")
    (property "Tolerance" "")
    (property "Val" "0R")
    (property "dnp" "")
    (property "exclude_from_bom" "")
    (property "ki_description" "0R resistor in 0402 package with unspecified tolerance")
    (attr exclude_from_pos_files exclude_from_bom)
    (fp_text reference "R179" (at -0.71 0.355 180) (layer "B.SilkS")
        (effects (font (size 0.7 0.7) (thickness 0.15)) (justify left bottom mirror))
    )
    (fp_text value "R_0R_0402" (at 0 -1.4 180) (layer "B.Fab") hide
        (effects (font (size 0.7 0.7) (thickness 0.15)) (justify left bottom mirror))
    )
    (fp_text user "${REFERENCE}" (at -0.95 -3.168 180) (layer "B.Fab") hide
        (effects (font (size 0.7 0.7) (thickness 0.15)) (justify left bottom mirror))
    )
    (fp_text user "License: Apache-2.0" (at -0.95 -5.169 180) (layer "B.Fab") hide
        (effects (font (size 0.7 0.7) (thickness 0.15)) (justify left bottom mirror))
    )
    (fp_text user "Author: Antmicro" (at -0.95 -4.169 180) (layer "B.Fab") hide
        (effects (font (size 0.7 0.7) (thickness 0.15)) (justify left bottom mirror))
    )
    (fp_rect (start -0.93 0.47) (end 0.93 -0.47)
      (stroke (width 0.05) (type solid)) (fill none) (layer "B.CrtYd"))
    (fp_rect (start -0.5 0.25) (end 0.5 -0.25)
      (stroke (width 0.15) (type solid)) (fill none) (layer "B.Fab"))
    (pad "1" smd roundrect (at -0.485 0) (size 0.59 0.64) (layers "B.Cu" "B.Paste" "B.Mask") (roundrect_rratio 0.25)
      (net 604 "GNDD") (pintype "passive"))
    (pad "2" smd roundrect (at 0.485 0) (size 0.59 0.64) (layers "B.Cu" "B.Paste" "B.Mask") (roundrect_rratio 0.25)
      (net 621 "/Ethernet/IRSHDL_EN") (pintype "passive"))
  )
)
